(kicad_pcb
	(version 20241229)
	(generator "pcbnew")
	(generator_version "9.0")
	(general
		(thickness 1.59)
		(legacy_teardrops no)
	)
	(paper "A3")
	(title_block
		(title "usb-c-power-adapter")
		(date "2025-06-24")
		(rev "1.1.2")
		(company "Antmicro")
		(comment 9 "footprints 61-67 of 122")
	)
	(layers
		(0 "F.Cu" signal)
		(4 "In1.Cu" signal)
		(6 "In2.Cu" signal)
		(2 "B.Cu" signal)
		(9 "F.Adhes" user "F.Adhesive")
		(11 "B.Adhes" user "B.Adhesive")
		(13 "F.Paste" user)
		(15 "B.Paste" user)
		(5 "F.SilkS" user "F.Silkscreen")
		(7 "B.SilkS" user "B.Silkscreen")
		(1 "F.Mask" user)
		(3 "B.Mask" user)
		(17 "Dwgs.User" user "User.Drawings")
		(19 "Cmts.User" user "User.Comments")
		(21 "Eco1.User" user "User.Eco1")
		(23 "Eco2.User" user "User.Eco2")
		(25 "Edge.Cuts" user)
		(27 "Margin" user)
		(31 "F.CrtYd" user "F.Courtyard")
		(29 "B.CrtYd" user "B.Courtyard")
		(35 "F.Fab" user)
		(33 "B.Fab" user)
	)
	(footprint "antmicro-footprints:C_0402_1005Metric"
		(layer "F.Cu")
		(at 89 67.2 180)
		(descr "Capacitor SMD 0402")
		(tags "capacitor SMD 0402")
		(property "Reference" "C28"
			(at -1 -0.8 0)
			(layer "F.SilkS")
			(effects
				(font
					(size 0.7 0.7)
					(thickness 0.15)
				)
				(justify left bottom)
			)
		)
		(property "Value" "C_100n_50V_X8L_0402"
			(at -1.022927 2.155213 0)
			(layer "F.Fab")
			(effects
				(font
					(size 0.7 0.7)
					(thickness 0.15)
				)
				(justify right bottom)
			)
		)
		(property "Datasheet" "https://www.murata.com/products/productdetail?partno=GCM155L8EH104KE07%23"
			(at 0 0 180)
			(layer "F.Fab")
			(hide yes)
			(effects
				(font
					(size 1.27 1.27)
					(thickness 0.15)
				)
			)
		)
		(property "Description" "SMD Multilayer Ceramic Capacitor, 100nF, 50V, 0402, ±10%, X8L"
			(at 0 0 180)
			(layer "F.Fab")
			(hide yes)
			(effects
				(font
					(size 1.27 1.27)
					(thickness 0.15)
				)
			)
		)
		(property "MPN" "GCM155L8EH104KE07D"
			(at 0 0 180)
			(unlocked yes)
			(layer "F.Fab")
			(hide yes)
			(effects
				(font
					(size 1 1)
					(thickness 0.15)
				)
			)
		)
		(property "Val" "100n"
			(at 0 0 180)
			(unlocked yes)
			(layer "F.Fab")
			(hide yes)
			(effects
				(font
					(size 1 1)
					(thickness 0.15)
				)
			)
		)
		(property "Voltage" "50V"
			(at 0 0 180)
			(unlocked yes)
			(layer "F.Fab")
			(hide yes)
			(effects
				(font
					(size 1 1)
					(thickness 0.15)
				)
			)
		)
		(property "Dielectric" "X8L"
			(at 0 0 180)
			(unlocked yes)
			(layer "F.Fab")
			(hide yes)
			(effects
				(font
					(size 1 1)
					(thickness 0.15)
				)
			)
		)
		(property "Manufacturer" "Murata"
			(at 0 0 180)
			(unlocked yes)
			(layer "F.Fab")
			(hide yes)
			(effects
				(font
					(size 1 1)
					(thickness 0.15)
				)
			)
		)
		(property "License" "Apache-2.0"
			(at 0 0 180)
			(unlocked yes)
			(layer "F.Fab")
			(hide yes)
			(effects
				(font
					(size 1 1)
					(thickness 0.15)
				)
			)
		)
		(property "Author" "Antmicro"
			(at 0 0 180)
			(unlocked yes)
			(layer "F.Fab")
			(hide yes)
			(effects
				(font
					(size 1 1)
					(thickness 0.15)
				)
			)
		)
		(sheetname "/USB PD/")
		(sheetfile "usb_pd.kicad_sch")
		(attr smd)
		(fp_rect
			(start -0.925 -0.47)
			(end 0.925 0.47)
			(stroke
				(width 0.05)
				(type default)
			)
			(fill no)
			(layer "F.CrtYd")
		)
		(fp_line
			(start 0.504 0.248)
			(end -0.494 0.248)
			(stroke
				(width 0.15)
				(type solid)
			)
			(layer "F.Fab")
		)
		(fp_line
			(start 0.504 -0.25)
			(end 0.504 0.248)
			(stroke
				(width 0.15)
				(type solid)
			)
			(layer "F.Fab")
		)
		(fp_line
			(start -0.494 0.248)
			(end -0.494 -0.25)
			(stroke
				(width 0.15)
				(type solid)
			)
			(layer "F.Fab")
		)
		(fp_line
			(start -0.494 -0.25)
			(end 0.504 -0.25)
			(stroke
				(width 0.15)
				(type solid)
			)
			(layer "F.Fab")
		)
		(pad "1" smd roundrect
			(at -0.48 0 180)
			(size 0.59 0.64)
			(layers "F.Cu" "F.Mask" "F.Paste")
			(roundrect_rratio 0.25)
			(net 2 "GND")
			(pintype "passive")
		)
		(pad "2" smd roundrect
			(at 0.48 0 180)
			(size 0.59 0.64)
			(layers "F.Cu" "F.Mask" "F.Paste")
			(roundrect_rratio 0.25)
			(net 61 "/USB PD/QWIIC_VCC")
			(pintype "passive")
		)
	)
	(footprint "antmicro-footprints:C_0402_1005Metric"
		(layer "F.Cu")
		(at 94.8 80.3 -90)
		(descr "Capacitor SMD 0402")
		(tags "capacitor SMD 0402")
		(property "Reference" "C10"
			(at 0.8529 -8.0514 180)
			(layer "B.SilkS")
			(effects
				(font
					(size 0.7 0.7)
					(thickness 0.15)
				)
				(justify left bottom mirror)
			)
		)
		(property "Value" "C_100n_50V_X8L_0402"
			(at -1.022927 2.155213 90)
			(layer "F.Fab")
			(effects
				(font
					(size 0.7 0.7)
					(thickness 0.15)
				)
				(justify right bottom)
			)
		)
		(property "Datasheet" "https://www.murata.com/products/productdetail?partno=GCM155L8EH104KE07%23"
			(at 0 0 270)
			(layer "F.Fab")
			(hide yes)
			(effects
				(font
					(size 1.27 1.27)
					(thickness 0.15)
				)
			)
		)
		(property "Description" "SMD Multilayer Ceramic Capacitor, 100nF, 50V, 0402, ±10%, X8L"
			(at 0 0 270)
			(layer "F.Fab")
			(hide yes)
			(effects
				(font
					(size 1.27 1.27)
					(thickness 0.15)
				)
			)
		)
		(property "MPN" "GCM155L8EH104KE07D"
			(at 0 0 270)
			(unlocked yes)
			(layer "F.Fab")
			(hide yes)
			(effects
				(font
					(size 1 1)
					(thickness 0.15)
				)
			)
		)
		(property "Val" "100n"
			(at 0 0 270)
			(unlocked yes)
			(layer "F.Fab")
			(hide yes)
			(effects
				(font
					(size 1 1)
					(thickness 0.15)
				)
			)
		)
		(property "Voltage" "50V"
			(at 0 0 270)
			(unlocked yes)
			(layer "F.Fab")
			(hide yes)
			(effects
				(font
					(size 1 1)
					(thickness 0.15)
				)
			)
		)
		(property "Dielectric" "X8L"
			(at 0 0 270)
			(unlocked yes)
			(layer "F.Fab")
			(hide yes)
			(effects
				(font
					(size 1 1)
					(thickness 0.15)
				)
			)
		)
		(property "Manufacturer" "Murata"
			(at 0 0 270)
			(unlocked yes)
			(layer "F.Fab")
			(hide yes)
			(effects
				(font
					(size 1 1)
					(thickness 0.15)
				)
			)
		)
		(property "License" "Apache-2.0"
			(at 0 0 270)
			(unlocked yes)
			(layer "F.Fab")
			(hide yes)
			(effects
				(font
					(size 1 1)
					(thickness 0.15)
				)
			)
		)
		(property "Author" "Antmicro"
			(at 0 0 270)
			(unlocked yes)
			(layer "F.Fab")
			(hide yes)
			(effects
				(font
					(size 1 1)
					(thickness 0.15)
				)
			)
		)
		(sheetname "/DC-DC Converters/")
		(sheetfile "dc-dc_converters.kicad_sch")
		(attr smd)
		(fp_rect
			(start -0.925 -0.47)
			(end 0.925 0.47)
			(stroke
				(width 0.05)
				(type default)
			)
			(fill no)
			(layer "F.CrtYd")
		)
		(fp_line
			(start -0.494 0.248)
			(end -0.494 -0.25)
			(stroke
				(width 0.15)
				(type solid)
			)
			(layer "F.Fab")
		)
		(fp_line
			(start 0.504 0.248)
			(end -0.494 0.248)
			(stroke
				(width 0.15)
				(type solid)
			)
			(layer "F.Fab")
		)
		(fp_line
			(start -0.494 -0.25)
			(end 0.504 -0.25)
			(stroke
				(width 0.15)
				(type solid)
			)
			(layer "F.Fab")
		)
		(fp_line
			(start 0.504 -0.25)
			(end 0.504 0.248)
			(stroke
				(width 0.15)
				(type solid)
			)
			(layer "F.Fab")
		)
		(pad "1" smd roundrect
			(at -0.48 0 270)
			(size 0.59 0.64)
			(layers "F.Cu" "F.Mask" "F.Paste")
			(roundrect_rratio 0.25)
			(net 16 "Net-(C10-Pad1)")
			(pintype "passive")
		)
		(pad "2" smd roundrect
			(at 0.48 0 270)
			(size 0.59 0.64)
			(layers "F.Cu" "F.Mask" "F.Paste")
			(roundrect_rratio 0.25)
			(net 17 "Net-(U2-BOOT)")
			(pintype "passive")
		)
	)
	(footprint "antmicro-footprints:TP_SMD_0.75mm"
		(layer "F.Cu")
		(at 86.576 76.45)
		(property "Reference" "TP11"
			(at -9.057 3.202 0)
			(layer "F.SilkS")
			(hide yes)
			(effects
				(font
					(size 0.7 0.7)
					(thickness 0.15)
				)
				(justify left bottom)
			)
		)
		(property "Value" "TP_0.75mm_SMD"
			(at 0 1.2 0)
			(layer "F.Fab")
			(effects
				(font
					(size 0.7 0.7)
					(thickness 0.15)
				)
				(justify left bottom)
			)
		)
		(property "Description" "SMT test point"
			(at 0 0 0)
			(layer "F.Fab")
			(hide yes)
			(effects
				(font
					(size 1.27 1.27)
					(thickness 0.15)
				)
			)
		)
		(property "MPN" ""
			(at 0 0 0)
			(unlocked yes)
			(layer "F.Fab")
			(hide yes)
			(effects
				(font
					(size 1 1)
					(thickness 0.15)
				)
			)
		)
		(property "Manufacturer" ""
			(at 0 0 0)
			(unlocked yes)
			(layer "F.Fab")
			(hide yes)
			(effects
				(font
					(size 1 1)
					(thickness 0.15)
				)
			)
		)
		(property "Author" "Antmicro"
			(at 0 0 0)
			(unlocked yes)
			(layer "F.Fab")
			(hide yes)
			(effects
				(font
					(size 1 1)
					(thickness 0.15)
				)
			)
		)
		(property "License" "Apache-2.0"
			(at 0 0 0)
			(unlocked yes)
			(layer "F.Fab")
			(hide yes)
			(effects
				(font
					(size 1 1)
					(thickness 0.15)
				)
			)
		)
		(sheetname "/USB PD/")
		(sheetfile "usb_pd.kicad_sch")
		(attr exclude_from_bom)
		(fp_circle
			(center 0 0)
			(end 0.475 0)
			(stroke
				(width 0.05)
				(type default)
			)
			(fill no)
			(layer "F.CrtYd")
		)
		(pad "1" smd circle
			(at 0 0)
			(size 0.75 0.75)
			(layers "F.Cu" "F.Mask")
			(net 56 "Net-(U1-A_B_SIDE)")
			(pinfunction "1")
			(pintype "passive")
		)
	)
	(footprint "antmicro-footprints:R_0402_1005Metric"
		(layer "F.Cu")
		(at 100.25 86.6)
		(descr "Resistor SMD 0402")
		(tags "resistor SMD 0402")
		(property "Reference" "R16"
			(at 0.842 0.522 0)
			(layer "F.SilkS")
			(effects
				(font
					(size 0.7 0.7)
					(thickness 0.15)
				)
				(justify left bottom)
			)
		)
		(property "Value" "R_316k_0402"
			(at -1.011843 1.772047 0)
			(layer "F.Fab")
			(effects
				(font
					(size 0.7 0.7)
					(thickness 0.15)
				)
				(justify left bottom)
			)
		)
		(property "Datasheet" "https://www.bourns.com/docs/product-datasheets/cr.pdf"
			(at 0 0 0)
			(layer "F.Fab")
			(hide yes)
			(effects
				(font
					(size 1.27 1.27)
					(thickness 0.15)
				)
			)
		)
		(property "Description" "SMD Chip Resistor"
			(at 0 0 0)
			(layer "F.Fab")
			(hide yes)
			(effects
				(font
					(size 1.27 1.27)
					(thickness 0.15)
				)
			)
		)
		(property "Manufacturer" "Bourns"
			(at 0 0 0)
			(unlocked yes)
			(layer "F.Fab")
			(hide yes)
			(effects
				(font
					(size 1 1)
					(thickness 0.15)
				)
			)
		)
		(property "MPN" "CR0402-FX-3163GLF"
			(at 0 0 0)
			(unlocked yes)
			(layer "F.Fab")
			(hide yes)
			(effects
				(font
					(size 1 1)
					(thickness 0.15)
				)
			)
		)
		(property "Val" "316k"
			(at 0 0 0)
			(unlocked yes)
			(layer "F.Fab")
			(hide yes)
			(effects
				(font
					(size 1 1)
					(thickness 0.15)
				)
			)
		)
		(property "License" "Apache-2.0"
			(at 0 0 0)
			(unlocked yes)
			(layer "F.Fab")
			(hide yes)
			(effects
				(font
					(size 1 1)
					(thickness 0.15)
				)
			)
		)
		(property "Author" "Antmicro"
			(at 0 0 0)
			(unlocked yes)
			(layer "F.Fab")
			(hide yes)
			(effects
				(font
					(size 1 1)
					(thickness 0.15)
				)
			)
		)
		(property "Tolerance" "1%"
			(at 0 0 0)
			(unlocked yes)
			(layer "F.Fab")
			(hide yes)
			(effects
				(font
					(size 1 1)
					(thickness 0.15)
				)
			)
		)
		(sheetname "/DC-DC Converters/")
		(sheetfile "dc-dc_converters.kicad_sch")
		(attr smd exclude_from_pos_files exclude_from_bom dnp)
		(fp_rect
			(start -0.925 -0.47)
			(end 0.925 0.47)
			(stroke
				(width 0.05)
				(type default)
			)
			(fill no)
			(layer "F.CrtYd")
		)
		(fp_rect
			(start -0.5 -0.25)
			(end 0.5 0.25)
			(stroke
				(width 0.15)
				(type solid)
			)
			(fill no)
			(layer "F.Fab")
		)
		(pad "1" smd roundrect
			(at -0.48 0)
			(size 0.59 0.64)
			(layers "F.Cu" "F.Mask" "F.Paste")
			(roundrect_rratio 0.25)
			(net 50 "Net-(R16-Pad1)")
			(pintype "passive")
		)
		(pad "2" smd roundrect
			(at 0.48 0)
			(size 0.59 0.64)
			(layers "F.Cu" "F.Mask" "F.Paste")
			(roundrect_rratio 0.25)
			(net 4 "Net-(C13-Pad1)")
			(pintype "passive")
		)
	)
	(footprint "antmicro-footprints:TP_SMD_0.75mm"
		(layer "F.Cu")
		(at 90.626 89.875)
		(property "Reference" "TP5"
			(at -9.996 -1.3292 0)
			(layer "F.SilkS")
			(hide yes)
			(effects
				(font
					(size 0.7 0.7)
					(thickness 0.15)
				)
				(justify left bottom)
			)
		)
		(property "Value" "TP_0.75mm_SMD"
			(at 0 1.2 0)
			(layer "F.Fab")
			(effects
				(font
					(size 0.7 0.7)
					(thickness 0.15)
				)
				(justify left bottom)
			)
		)
		(property "Description" "SMT test point"
			(at 0 0 0)
			(layer "F.Fab")
			(hide yes)
			(effects
				(font
					(size 1.27 1.27)
					(thickness 0.15)
				)
			)
		)
		(property "MPN" ""
			(at 0 0 0)
			(unlocked yes)
			(layer "F.Fab")
			(hide yes)
			(effects
				(font
					(size 1 1)
					(thickness 0.15)
				)
			)
		)
		(property "Manufacturer" ""
			(at 0 0 0)
			(unlocked yes)
			(layer "F.Fab")
			(hide yes)
			(effects
				(font
					(size 1 1)
					(thickness 0.15)
				)
			)
		)
		(property "Author" "Antmicro"
			(at 0 0 0)
			(unlocked yes)
			(layer "F.Fab")
			(hide yes)
			(effects
				(font
					(size 1 1)
					(thickness 0.15)
				)
			)
		)
		(property "License" "Apache-2.0"
			(at 0 0 0)
			(unlocked yes)
			(layer "F.Fab")
			(hide yes)
			(effects
				(font
					(size 1 1)
					(thickness 0.15)
				)
			)
		)
		(sheetname "/DC-DC Converters/")
		(sheetfile "dc-dc_converters.kicad_sch")
		(attr exclude_from_bom)
		(fp_circle
			(center 0 0)
			(end 0.475 0)
			(stroke
				(width 0.05)
				(type default)
			)
			(fill no)
			(layer "F.CrtYd")
		)
		(pad "1" smd circle
			(at 0 0)
			(size 0.75 0.75)
			(layers "F.Cu" "F.Mask")
			(net 25 "+5V")
			(pinfunction "1")
			(pintype "passive")
		)
	)
	(footprint "antmicro-footprints:R_0402_1005Metric"
		(layer "F.Cu")
		(at 86.026 77.575)
		(descr "Resistor SMD 0402")
		(tags "resistor SMD 0402")
		(property "Reference" "R21"
			(at -1.057 2.202 180)
			(layer "F.SilkS")
			(effects
				(font
					(size 0.7 0.7)
					(thickness 0.15)
				)
				(justify left bottom)
			)
		)
		(property "Value" "R_100k_0402"
			(at -1.011843 1.772047 0)
			(layer "F.Fab")
			(effects
				(font
					(size 0.7 0.7)
					(thickness 0.15)
				)
				(justify left bottom)
			)
		)
		(property "Datasheet" "https://www.bourns.com/docs/product-datasheets/cr.pdf"
			(at 0 0 0)
			(layer "F.Fab")
			(hide yes)
			(effects
				(font
					(size 1.27 1.27)
					(thickness 0.15)
				)
			)
		)
		(property "Description" "SMD Chip Resistor, 100 kohm, ± 1%, 62.5 mW, 0402 [1005 Metric], Thick Film, General Purpose"
			(at 0 0 0)
			(layer "F.Fab")
			(hide yes)
			(effects
				(font
					(size 1.27 1.27)
					(thickness 0.15)
				)
			)
		)
		(property "MPN" "CR0402-FX-1003GLF"
			(at 0 0 0)
			(unlocked yes)
			(layer "F.Fab")
			(hide yes)
			(effects
				(font
					(size 1 1)
					(thickness 0.15)
				)
			)
		)
		(property "Manufacturer" "Bourns"
			(at 0 0 0)
			(unlocked yes)
			(layer "F.Fab")
			(hide yes)
			(effects
				(font
					(size 1 1)
					(thickness 0.15)
				)
			)
		)
		(property "License" "Apache-2.0"
			(at 0 0 0)
			(unlocked yes)
			(layer "F.Fab")
			(hide yes)
			(effects
				(font
					(size 1 1)
					(thickness 0.15)
				)
			)
		)
		(property "Author" "Antmicro"
			(at 0 0 0)
			(unlocked yes)
			(layer "F.Fab")
			(hide yes)
			(effects
				(font
					(size 1 1)
					(thickness 0.15)
				)
			)
		)
		(property "Val" "100k"
			(at 0 0 0)
			(unlocked yes)
			(layer "F.Fab")
			(hide yes)
			(effects
				(font
					(size 1 1)
					(thickness 0.15)
				)
			)
		)
		(property "Tolerance" "1%"
			(at 0 0 0)
			(unlocked yes)
			(layer "F.Fab")
			(hide yes)
			(effects
				(font
					(size 1 1)
					(thickness 0.15)
				)
			)
		)
		(sheetname "/USB PD/")
		(sheetfile "usb_pd.kicad_sch")
		(attr smd)
		(fp_rect
			(start -0.925 -0.47)
			(end 0.925 0.47)
			(stroke
				(width 0.05)
				(type default)
			)
			(fill no)
			(layer "F.CrtYd")
		)
		(fp_rect
			(start -0.5 -0.25)
			(end 0.5 0.25)
			(stroke
				(width 0.15)
				(type solid)
			)
			(fill no)
			(layer "F.Fab")
		)
		(pad "1" smd roundrect
			(at -0.48 0)
			(size 0.59 0.64)
			(layers "F.Cu" "F.Mask" "F.Paste")
			(roundrect_rratio 0.25)
			(net 7 "Net-(Q1-G)")
			(pintype "passive")
		)
		(pad "2" smd roundrect
			(at 0.48 0)
			(size 0.59 0.64)
			(layers "F.Cu" "F.Mask" "F.Paste")
			(roundrect_rratio 0.25)
			(net 6 "VBUS")
			(pintype "passive")
		)
	)
	(footprint "antmicro-footprints:R_0402_1005Metric"
		(layer "F.Cu")
		(at 84.35 69.75 90)
		(descr "Resistor SMD 0402")
		(tags "resistor SMD 0402")
		(property "Reference" "R4"
			(at 1.17 0.486 90)
			(layer "F.SilkS")
			(effects
				(font
					(size 0.7 0.7)
					(thickness 0.15)
				)
				(justify left bottom)
			)
		)
		(property "Value" "R_10k_0402"
			(at -1.011843 1.772047 90)
			(layer "F.Fab")
			(effects
				(font
					(size 0.7 0.7)
					(thickness 0.15)
				)
				(justify left bottom)
			)
		)
		(property "Datasheet" "https://www.bourns.com/docs/product-datasheets/cr.pdf"
			(at 0 0 90)
			(layer "F.Fab")
			(hide yes)
			(effects
				(font
					(size 1.27 1.27)
					(thickness 0.15)
				)
			)
		)
		(property "Description" "SMD Chip Resistor, 10 kohm, ± 1%, 62.5 mW, 0402 [1005 Metric], Thick Film, General Purpose"
			(at 0 0 90)
			(layer "F.Fab")
			(hide yes)
			(effects
				(font
					(size 1.27 1.27)
					(thickness 0.15)
				)
			)
		)
		(property "MPN" "CR0402-FX-1002GLF"
			(at 0 0 90)
			(unlocked yes)
			(layer "F.Fab")
			(hide yes)
			(effects
				(font
					(size 1 1)
					(thickness 0.15)
				)
			)
		)
		(property "Manufacturer" "Bourns"
			(at 0 0 90)
			(unlocked yes)
			(layer "F.Fab")
			(hide yes)
			(effects
				(font
					(size 1 1)
					(thickness 0.15)
				)
			)
		)
		(property "License" "Apache-2.0"
			(at 0 0 90)
			(unlocked yes)
			(layer "F.Fab")
			(hide yes)
			(effects
				(font
					(size 1 1)
					(thickness 0.15)
				)
			)
		)
		(property "Author" "Antmicro"
			(at 0 0 90)
			(unlocked yes)
			(layer "F.Fab")
			(hide yes)
			(effects
				(font
					(size 1 1)
					(thickness 0.15)
				)
			)
		)
		(property "Val" "10k"
			(at 0 0 90)
			(unlocked yes)
			(layer "F.Fab")
			(hide yes)
			(effects
				(font
					(size 1 1)
					(thickness 0.15)
				)
			)
		)
		(property "Tolerance" "1%"
			(at 0 0 90)
			(unlocked yes)
			(layer "F.Fab")
			(hide yes)
			(effects
				(font
					(size 1 1)
					(thickness 0.15)
				)
			)
		)
		(sheetname "/USB PD/")
		(sheetfile "usb_pd.kicad_sch")
		(attr smd)
		(fp_rect
			(start -0.925 -0.47)
			(end 0.925 0.47)
			(stroke
				(width 0.05)
				(type default)
			)
			(fill no)
			(layer "F.CrtYd")
		)
		(fp_rect
			(start -0.5 -0.25)
			(end 0.5 0.25)
			(stroke
				(width 0.15)
				(type solid)
			)
			(fill no)
			(layer "F.Fab")
		)
		(pad "1" smd roundrect
			(at -0.48 0 90)
			(size 0.59 0.64)
			(layers "F.Cu" "F.Mask" "F.Paste")
			(roundrect_rratio 0.25)
			(net 42 "Net-(U1-RESET)")
			(pintype "passive")
		)
		(pad "2" smd roundrect
			(at 0.48 0 90)
			(size 0.59 0.64)
			(layers "F.Cu" "F.Mask" "F.Paste")
			(roundrect_rratio 0.25)
			(net 2 "GND")
			(pintype "passive")
		)
	)
)
